# T6G (Grand Teton) — schematic netlist excerpt (pin names and nets, part order shuffled) for the footprints in the layout excerpt that follows; sources: Cadence DE-HDL packaged netlist, KiCad conversion of 04192023_DAF0TMB3IC0_F0TG_MB_C_brd_V02_OCP.brd

PU23  ISL99390FRZTR5935  ISL99390FRZ-TR5935 IC  pkg QFN21_6X5XB  page 208
  VOS  = PVDD11_S3_P0_VOS2
  AGND  = GND
  VCC  = PVDD11_S3_P0_VCC2
  PVCC  = PVDD11_S3_P0_PVCC
  PGND1  = GND
  GL1  = NC_PVDD11_S3_P0_GL1_2
  PGND2  = GND
  SW  = SW_PVDD11_S3_P0_SW2
  VIN1  = SW_P12V_AUX_PVDD11_S3_P0_FLT
  VIN2  = SW_P12V_AUX_PVDD11_S3_P0_FLT
  DNC  = NC_PVDD11_S3_P0_DNC2
  PHASE  = SW_PVDD11_S3_P0_PH2
  BOOT  = SW_PVDD11_S3_P0_BOOT2
  PWM  = PVDD11_S3_P0_PWM2
  EN  = PVDD11_S3_P0_VCC2
  TOUT_FLT  = PVDD11_S3_P0_TEMP0
  LSET  = PVDD11_S3_P0_LSET2
  IOUT  = PVDD11_S3_P0_IMON2
  REFIN  = PVDD11_S3_P0_VCCS
  PGND3  = GND
  GL2  = NC_PVDD11_S3_P0_GL2_2

(kicad_pcb
	(version 20260206)
	(generator "pcbnew")
	(generator_version "10.0")
	(general
		(thickness 1.6)
		(legacy_teardrops no)
	)
	(paper "A4")
	(title_block
		(title "04192023_DAF0TMB3IC0_F0TG_MB_C_brd_V02_OCP.brd")
		(comment 1 "Grand Teton / footprints 106-106 of 8354")
	)
	(layers
		(0 "F.Cu" signal "TOP")
		(4 "In1.Cu" signal "GND")
		(6 "In2.Cu" signal "IN1")
		(8 "In3.Cu" signal "GND1")
		(10 "In4.Cu" signal "IN2")
		(12 "In5.Cu" signal "GND2")
		(14 "In6.Cu" signal "IN3")
		(16 "In7.Cu" signal "GND3")
		(18 "In8.Cu" signal "VCC")
		(20 "In9.Cu" signal "VCC1")
		(22 "In10.Cu" signal "GND4")
		(24 "In11.Cu" signal "IN4")
		(26 "In12.Cu" signal "GND5")
		(28 "In13.Cu" signal "IN5")
		(30 "In14.Cu" signal "GND6")
		(32 "In15.Cu" signal "IN6")
		(34 "In16.Cu" signal "GND7")
		(2 "B.Cu" signal "BOTTOM")
		(9 "F.Adhes" user "F.Adhesive")
		(11 "B.Adhes" user "B.Adhesive")
		(13 "F.Paste" user "Package Geometry/Pastemask Top")
		(15 "B.Paste" user "Package Geometry/Pastemask Bottom")
		(5 "F.SilkS" user "Ref Des/Silkscreen Top")
		(7 "B.SilkS" user "Ref Des/Silkscreen Bottom")
		(1 "F.Mask" user "Board Geometry/Soldermask Top")
		(3 "B.Mask" user "Board Geometry/Soldermask Bottom")
		(17 "Dwgs.User" user "User.Drawings")
		(19 "Cmts.User" user "User.Comments")
		(21 "Eco1.User" user "User.Eco1")
		(23 "Eco2.User" user "User.Eco2")
		(25 "Edge.Cuts" user "Board Geometry/Outline")
		(27 "Margin" user)
		(31 "F.CrtYd" user "Package Geometry/Place Bound Top")
		(29 "B.CrtYd" user "Package Geometry/Place Bound Bottom")
		(35 "F.Fab" user "Ref Des/Assembly Top")
		(33 "B.Fab" user "Ref Des/Assembly Bottom")
	)
	(footprint ""
		(layer "F.Cu")
		(at 431.970688 -351.140268)
		(property "Reference" "PU23"
			(at 5.206238 -1.0922 90)
			(unlocked yes)
			(layer "F.SilkS")
			(effects
				(font
					(size 0.7874 0.5842)
					(thickness 0.1524)
				)
				(justify left)
			)
		)
		(property "Value" ""
			(at 0 0 0)
			(layer "F.Fab")
			(effects
				(font
					(size 1.27 1.27)
				)
			)
		)
		(duplicate_pad_numbers_are_jumpers no)
		(fp_line
			(start -2.500122 -2.999994)
			(end -2.24409 -2.999994)
			(stroke
				(width 0.1524)
				(type default)
			)
			(layer "F.SilkS")
		)
		(fp_line
			(start -2.500122 -2.529078)
			(end -2.500122 -2.999994)
			(stroke
				(width 0.1524)
				(type default)
			)
			(layer "F.SilkS")
		)
		(fp_line
			(start -2.500122 0.6604)
			(end -2.500122 0.229108)
			(stroke
				(width 0.1524)
				(type default)
			)
			(layer "F.SilkS")
		)
		(fp_line
			(start -2.500122 2.999994)
			(end -2.500122 2.339594)
			(stroke
				(width 0.1524)
				(type default)
			)
			(layer "F.SilkS")
		)
		(fp_line
			(start -2.2987 2.999994)
			(end -2.500122 2.999994)
			(stroke
				(width 0.1524)
				(type default)
			)
			(layer "F.SilkS")
		)
		(fp_line
			(start 2.31394 -2.999994)
			(end 2.500122 -2.999994)
			(stroke
				(width 0.1524)
				(type default)
			)
			(layer "F.SilkS")
		)
		(fp_line
			(start 2.500122 -2.999994)
			(end 2.500122 -2.44348)
			(stroke
				(width 0.1524)
				(type default)
			)
			(layer "F.SilkS")
		)
		(fp_line
			(start 2.500122 2.339594)
			(end 2.500122 2.999994)
			(stroke
				(width 0.1524)
				(type default)
			)
			(layer "F.SilkS")
		)
		(fp_line
			(start 2.500122 2.999994)
			(end 2.2987 2.999994)
			(stroke
				(width 0.1524)
				(type default)
			)
			(layer "F.SilkS")
		)
		(fp_poly
			(pts
				(xy -3.43535 -2.660142) (xy -2.99339 -3.102356) (xy -2.771902 -2.438908)
			)
			(stroke
				(width 0)
				(type default)
			)
			(fill yes)
			(layer "F.SilkS")
		)
		(fp_line
			(start -2.500122 -2.999994)
			(end 2.500122 -2.999994)
			(stroke
				(width 0.1)
				(type default)
			)
			(layer "F.Fab")
		)
		(fp_line
			(start -2.500122 2.999994)
			(end -2.500122 -2.999994)
			(stroke
				(width 0.1)
				(type default)
			)
			(layer "F.Fab")
		)
		(fp_line
			(start 2.500122 -2.999994)
			(end 2.500122 2.999994)
			(stroke
				(width 0.1)
				(type default)
			)
			(layer "F.Fab")
		)
		(fp_line
			(start 2.500122 2.999994)
			(end -2.500122 2.999994)
			(stroke
				(width 0.1)
				(type default)
			)
			(layer "F.Fab")
		)
		(fp_poly
			(pts
				(xy -4.218432 -2.783078) (xy -4.218432 -1.767078) (xy -3.202432 -2.275078)
			)
			(stroke
				(width 0)
				(type default)
			)
			(fill yes)
			(layer "F.Fab")
		)
		(pad "1" smd rect
			(at -2.400046 -2.275078 90)
			(size 0.2286 0.6096)
			(layers "F.Cu" "F.Mask" "F.Paste")
			(net "PVDD11_S3_P0_VOS2")
		)
		(pad "2" smd rect
			(at -2.400046 -1.82499 90)
			(size 0.2286 0.6096)
			(layers "F.Cu" "F.Mask" "F.Paste")
			(net "GND")
		)
		(pad "3" smd rect
			(at -2.400046 -1.374902 90)
			(size 0.2286 0.6096)
			(layers "F.Cu" "F.Mask" "F.Paste")
			(net "PVDD11_S3_P0_VCC2")
		)
		(pad "4" smd rect
			(at -2.400046 -0.925068 90)
			(size 0.2286 0.6096)
			(layers "F.Cu" "F.Mask" "F.Paste")
			(net "PVDD11_S3_P0_PVCC")
		)
		(pad "5" smd rect
			(at -2.400046 -0.47498 90)
			(size 0.2286 0.6096)
			(layers "F.Cu" "F.Mask" "F.Paste")
			(net "GND")
		)
		(pad "6" smd rect
			(at -2.400046 -0.024892 90)
			(size 0.2286 0.6096)
			(layers "F.Cu" "F.Mask" "F.Paste")
			(net "NC_PVDD11_S3_P0_GL1_2")
		)
		(pad "7_9-20_24" smd circle
			(at 0 1.150112 90)
			(size 0 0)
			(layers "F.Cu" "F.Mask" "F.Paste")
			(net "GND")
		)
		(pad "10_19" smd rect
			(at 0 2.899918 90)
			(size 0.6096 4.318)
			(layers "F.Cu" "F.Mask" "F.Paste")
			(net "SW_PVDD11_S3_P0_SW2")
		)
		(pad "25_29" smd rect
			(at 1.549908 -1.279906 270)
			(size 2.0574 2.3114)
			(layers "F.Cu" "F.Mask" "F.Paste")
			(net "SW_P12V_AUX_PVDD11_S3_P0_FLT")
		)
		(pad "30" smd rect
			(at 2.05994 -2.899918)
			(size 0.2286 0.6096)
			(layers "F.Cu" "F.Mask" "F.Paste")
			(net "SW_P12V_AUX_PVDD11_S3_P0_FLT")
		)
		(pad "31" smd rect
			(at 1.610106 -2.899918)
			(size 0.2286 0.6096)
			(layers "F.Cu" "F.Mask" "F.Paste")
			(net "NC_PVDD11_S3_P0_DNC2")
		)
		(pad "32" smd rect
			(at 1.160018 -2.899918)
			(size 0.2286 0.6096)
			(layers "F.Cu" "F.Mask" "F.Paste")
			(net "SW_PVDD11_S3_P0_PH2")
		)
		(pad "33" smd rect
			(at 0.70993 -2.899918)
			(size 0.2286 0.6096)
			(layers "F.Cu" "F.Mask" "F.Paste")
			(net "SW_PVDD11_S3_P0_BOOT2")
		)
		(pad "34" smd rect
			(at 0.260096 -2.899918)
			(size 0.2286 0.6096)
			(layers "F.Cu" "F.Mask" "F.Paste")
			(net "PVDD11_S3_P0_PWM2")
		)
		(pad "35" smd rect
			(at -0.189992 -2.899918)
			(size 0.2286 0.6096)
			(layers "F.Cu" "F.Mask" "F.Paste")
			(net "PVDD11_S3_P0_VCC2")
		)
		(pad "36" smd rect
			(at -0.64008 -2.899918)
			(size 0.2286 0.6096)
			(layers "F.Cu" "F.Mask" "F.Paste")
			(net "PVDD11_S3_P0_TEMP0")
		)
		(pad "37" smd rect
			(at -1.089914 -2.899918)
			(size 0.2286 0.6096)
			(layers "F.Cu" "F.Mask" "F.Paste")
			(net "PVDD11_S3_P0_LSET2")
		)
		(pad "38" smd rect
			(at -1.540002 -2.899918)
			(size 0.2286 0.6096)
			(layers "F.Cu" "F.Mask" "F.Paste")
			(net "PVDD11_S3_P0_IMON2")
		)
		(pad "39" smd rect
			(at -1.99009 -2.899918)
			(size 0.2286 0.6096)
			(layers "F.Cu" "F.Mask" "F.Paste")
			(net "PVDD11_S3_P0_VCCS")
		)
		(pad "40" smd rect
			(at -0.87503 -1.27508)
			(size 1.7526 1.9558)
			(layers "F.Cu" "F.Mask" "F.Paste")
			(net "GND")
		)
		(pad "41" smd rect
			(at -1.525016 0.249936 270)
			(size 0.3048 0.4572)
			(layers "F.Cu" "F.Mask" "F.Paste")
			(net "NC_PVDD11_S3_P0_GL2_2")
		)
		(zone
			(layer "F.Cu")
			(hatch none 0.5)
			(connect_pads
				(clearance 0)
			)
			(min_thickness 0.25)
			(keepout
				(tracks not_allowed)
				(vias allowed)
				(pads allowed)
				(copperpour not_allowed)
				(footprints allowed)
			)
			(placement
				(enabled no)
				(sheetname "")
			)
			(fill
				(thermal_gap 0.5)
				(thermal_bridge_width 0.5)
				(island_removal_mode 0)
			)
			(polygon
				(pts
					(xy 429.470566 -348.584266) (xy 429.470566 -348.889574) (xy 434.47081 -348.889574) (xy 434.47081 -348.140274)
					(xy 434.180488 -348.140274) (xy 434.180488 -348.59595) (xy 429.760888 -348.59595) (xy 429.760888 -348.584266)
				)
			)
		)
		(zone
			(layer "F.Cu")
			(hatch none 0.5)
			(connect_pads
				(clearance 0)
			)
			(min_thickness 0.25)
			(keepout
				(tracks not_allowed)
				(vias allowed)
				(pads allowed)
				(copperpour not_allowed)
				(footprints allowed)
			)
			(placement
				(enabled no)
				(sheetname "")
			)
			(fill
				(thermal_gap 0.5)
				(thermal_bridge_width 0.5)
				(island_removal_mode 0)
			)
			(polygon
				(pts
					(xy 432.022758 -351.38868) (xy 432.022758 -353.444048) (xy 430.168558 -353.444048) (xy 430.168558 -353.203002)
					(xy 429.926242 -353.203002) (xy 429.926242 -353.684586) (xy 433.731162 -353.684586) (xy 433.731162 -353.499674)
					(xy 432.314096 -353.499674) (xy 432.314096 -351.340674) (xy 434.47081 -351.340674) (xy 434.47081 -351.090992)
					(xy 432.320446 -351.090992)
				)
			)
		)
	)
)
